(kicad_pcb
	(version 20260206)
	(generator "pcbnew")
	(generator_version "10.0")
	(general
		(thickness 1.6)
		(legacy_teardrops no)
	)
	(paper "A4")
	(title_block
		(title "v2-pdb — ms_pdb_v2.brd")
		(comment 1 "Open CloudServer (Microsoft) / footprints 66-72 of 348")
	)
	(layers
		(0 "F.Cu" signal "TOP")
		(4 "In1.Cu" signal "GND")
		(6 "In2.Cu" signal "IN1")
		(8 "In3.Cu" signal "VCC")
		(10 "In4.Cu" signal "VCC1")
		(12 "In5.Cu" signal "IN2")
		(14 "In6.Cu" signal "GND1")
		(2 "B.Cu" signal "BOTTOM")
		(9 "F.Adhes" user "F.Adhesive")
		(11 "B.Adhes" user "B.Adhesive")
		(13 "F.Paste" user "Package Geometry/Pastemask Top")
		(15 "B.Paste" user "Package Geometry/Pastemask Bottom")
		(5 "F.SilkS" user "Ref Des/Silkscreen Top")
		(7 "B.SilkS" user "Ref Des/Silkscreen Bottom")
		(1 "F.Mask" user "Board Geometry/Soldermask Top")
		(3 "B.Mask" user "Board Geometry/Soldermask Bottom")
		(17 "Dwgs.User" user "User.Drawings")
		(19 "Cmts.User" user "User.Comments")
		(21 "Eco1.User" user "User.Eco1")
		(23 "Eco2.User" user "User.Eco2")
		(25 "Edge.Cuts" user "Board Geometry/Outline")
		(27 "Margin" user)
		(31 "F.CrtYd" user "Package Geometry/Place Bound Top")
		(29 "B.CrtYd" user "Package Geometry/Place Bound Bottom")
		(35 "F.Fab" user "Ref Des/Assembly Top")
		(33 "B.Fab" user "Ref Des/Assembly Bottom")
	)
	(footprint ""
		(layer "F.Cu")
		(at 5.70992 -86.47684)
		(property "Reference" "J34"
			(at -2.0066 -4.028948 0)
			(unlocked yes)
			(layer "F.SilkS")
			(effects
				(font
					(size 0.7874 0.5842)
					(thickness 0.1524)
				)
				(justify left)
			)
		)
		(property "Value" ""
			(at 0 0 0)
			(layer "F.Fab")
			(effects
				(font
					(size 1.27 1.27)
				)
			)
		)
		(duplicate_pad_numbers_are_jumpers no)
		(fp_line
			(start -3.10007 1.700022)
			(end -3.10007 4.299966)
			(stroke
				(width 0.1524)
				(type default)
			)
			(layer "F.SilkS")
		)
		(fp_line
			(start -3.10007 4.299966)
			(end -1.89992 4.299966)
			(stroke
				(width 0.1524)
				(type default)
			)
			(layer "F.SilkS")
		)
		(fp_line
			(start -1.89992 -3.325114)
			(end -1.89992 1.700022)
			(stroke
				(width 0.1524)
				(type default)
			)
			(layer "F.SilkS")
		)
		(fp_line
			(start -1.89992 1.700022)
			(end -3.10007 1.700022)
			(stroke
				(width 0.1524)
				(type default)
			)
			(layer "F.SilkS")
		)
		(fp_line
			(start -1.89992 4.299966)
			(end -1.89992 9.325102)
			(stroke
				(width 0.1524)
				(type default)
			)
			(layer "F.SilkS")
		)
		(fp_line
			(start -1.89992 9.325102)
			(end 1.016 9.325102)
			(stroke
				(width 0.1524)
				(type default)
			)
			(layer "F.SilkS")
		)
		(fp_line
			(start 1.016 -3.325114)
			(end -1.89992 -3.325114)
			(stroke
				(width 0.1524)
				(type default)
			)
			(layer "F.SilkS")
		)
		(fp_line
			(start 2.469896 8.133588)
			(end 2.469896 -2.128012)
			(stroke
				(width 0.1524)
				(type default)
			)
			(layer "F.SilkS")
		)
		(fp_poly
			(pts
				(xy -3.435604 0.672338) (xy -3.435604 -0.672338) (xy -2.090928 0)
			)
			(stroke
				(width 0)
				(type default)
			)
			(fill yes)
			(layer "F.SilkS")
		)
		(fp_poly
			(pts
				(xy -0.8636 6.860794) (xy 0.8636 6.860794) (xy 0.8636 -0.860806) (xy -0.8636 -0.860806)
			)
			(stroke
				(width 0)
				(type default)
			)
			(fill no)
			(layer "B.CrtYd")
		)
		(fp_poly
			(pts
				(arc
					(start 2.874518 -2.999994)
					(mid 1.045718 -2.999994)
					(end 2.874518 -2.999994)
				)
			)
			(stroke
				(width 0)
				(type default)
			)
			(fill no)
			(layer "B.CrtYd")
		)
		(fp_poly
			(pts
				(arc
					(start 2.874518 8.999982)
					(mid 1.045718 8.999982)
					(end 2.874518 8.999982)
				)
			)
			(stroke
				(width 0)
				(type default)
			)
			(fill no)
			(layer "B.CrtYd")
		)
		(fp_poly
			(pts
				(xy 2.469896 8.232394) (xy 2.469896 -2.232406) (xy 2.8956 -2.232406) (xy 2.8956 -3.934206) (xy 1.0922 -3.934206)
				(xy 1.0922 -3.325114) (xy -1.89992 -3.325114) (xy -1.89992 1.700022) (xy -3.10007 1.700022) (xy -3.10007 4.299966)
				(xy -1.89992 4.299966) (xy -1.89992 9.325102) (xy 1.0922 9.325102) (xy 1.0922 9.934194) (xy 2.8956 9.934194)
				(xy 2.8956 8.232394)
			)
			(stroke
				(width 0)
				(type default)
			)
			(fill no)
			(layer "F.CrtYd")
		)
		(fp_line
			(start -3.10007 1.700022)
			(end -3.10007 4.299966)
			(stroke
				(width 0.1)
				(type default)
			)
			(layer "F.Fab")
		)
		(fp_line
			(start -3.10007 4.299966)
			(end -1.89992 4.299966)
			(stroke
				(width 0.1)
				(type default)
			)
			(layer "F.Fab")
		)
		(fp_line
			(start -1.89992 -3.325114)
			(end -1.89992 1.700022)
			(stroke
				(width 0.1)
				(type default)
			)
			(layer "F.Fab")
		)
		(fp_line
			(start -1.89992 1.700022)
			(end -3.10007 1.700022)
			(stroke
				(width 0.1)
				(type default)
			)
			(layer "F.Fab")
		)
		(fp_line
			(start -1.89992 4.299966)
			(end -1.89992 9.325102)
			(stroke
				(width 0.1)
				(type default)
			)
			(layer "F.Fab")
		)
		(fp_line
			(start -1.89992 9.325102)
			(end 2.469896 9.325102)
			(stroke
				(width 0.1)
				(type default)
			)
			(layer "F.Fab")
		)
		(fp_line
			(start 2.469896 -3.325114)
			(end -1.89992 -3.325114)
			(stroke
				(width 0.1)
				(type default)
			)
			(layer "F.Fab")
		)
		(fp_line
			(start 2.469896 9.325102)
			(end 2.469896 -3.325114)
			(stroke
				(width 0.1)
				(type default)
			)
			(layer "F.Fab")
		)
		(fp_poly
			(pts
				(xy -3.435604 0.672338) (xy -3.435604 -0.672338) (xy -2.090928 0)
			)
			(stroke
				(width 0)
				(type default)
			)
			(fill yes)
			(layer "F.Fab")
		)
		(fp_text user "3"
			(at -2.504948 5.999988 90)
			(unlocked yes)
			(layer "F.SilkS")
			(effects
				(font
					(size 0.7874 0.5842)
					(thickness 0.1524)
				)
			)
		)
		(fp_text user "1"
			(at 0.035052 -1.188212 90)
			(unlocked yes)
			(layer "B.SilkS")
			(effects
				(font
					(size 0.7874 0.5842)
					(thickness 0.1524)
				)
				(justify mirror)
			)
		)
		(fp_text user "3"
			(at 0.035052 7.193788 90)
			(unlocked yes)
			(layer "B.SilkS")
			(effects
				(font
					(size 0.7874 0.5842)
					(thickness 0.1524)
				)
				(justify mirror)
			)
		)
		(fp_text user "1"
			(at 0.035052 -1.188212 90)
			(unlocked yes)
			(layer "B.Fab")
			(effects
				(font
					(size 0.7874 0.5842)
					(thickness 0.1524)
				)
				(justify mirror)
			)
		)
		(fp_text user "3"
			(at 0.035052 7.193788 90)
			(unlocked yes)
			(layer "B.Fab")
			(effects
				(font
					(size 0.7874 0.5842)
					(thickness 0.1524)
				)
				(justify mirror)
			)
		)
		(fp_text user "3"
			(at -2.504948 5.999988 90)
			(unlocked yes)
			(layer "F.Fab")
			(effects
				(font
					(size 0.7874 0.5842)
					(thickness 0.1524)
				)
			)
		)
		(pad "" np_thru_hole circle
			(at 1.960118 -2.999994 90)
			(size 1.3208 1.3208)
			(drill 1.3208)
			(layers "*.Cu" "*.Mask")
			(clearance 0.381)
			(thermal_gap 0.381)
		)
		(pad "" np_thru_hole circle
			(at 1.960118 8.999982 90)
			(size 1.3208 1.3208)
			(drill 1.3208)
			(layers "*.Cu" "*.Mask")
			(clearance 0.381)
			(thermal_gap 0.381)
		)
		(pad "1" thru_hole rect
			(at 0 0 90)
			(size 1.6002 1.6002)
			(drill 1.0922)
			(layers "*.Cu" "*.Mask")
			(remove_unused_layers no)
			(net "GND")
			(clearance 0)
			(padstack
				(mode front_inner_back)
				(layer "Inner"
					(shape circle)
					(size 1.6002 1.6002)
					(clearance 0)
				)
				(layer "B.Cu"
					(shape rect)
					(size 1.6002 1.6002)
					(clearance 0)
				)
			)
		)
		(pad "2" thru_hole circle
			(at 0 2.999994 90)
			(size 1.6002 1.6002)
			(drill 1.0922)
			(layers "*.Cu" "*.Mask")
			(remove_unused_layers no)
			(net "P12V")
			(clearance 0)
		)
		(pad "3" thru_hole circle
			(at 0 5.999988 90)
			(size 1.6002 1.6002)
			(drill 1.0922)
			(layers "*.Cu" "*.Mask")
			(remove_unused_layers no)
			(net "GND")
			(clearance 0)
		)
		(zone
			(layers "F.Cu" "B.Cu" "In1.Cu" "In2.Cu" "In3.Cu" "In4.Cu" "In5.Cu" "In6.Cu")
			(hatch none 0.5)
			(connect_pads
				(clearance 0)
			)
			(min_thickness 0.25)
			(keepout
				(tracks not_allowed)
				(vias allowed)
				(pads allowed)
				(copperpour not_allowed)
				(footprints allowed)
			)
			(placement
				(enabled no)
				(sheetname "")
			)
			(fill
				(thermal_gap 0.5)
				(thermal_bridge_width 0.5)
				(island_removal_mode 0)
			)
			(polygon
				(pts
					(arc
						(start 8.736838 -89.476834)
						(mid 6.603238 -89.476834)
						(end 8.736838 -89.476834)
					)
				)
			)
		)
		(zone
			(layers "F.Cu" "B.Cu" "In1.Cu" "In2.Cu" "In3.Cu" "In4.Cu" "In5.Cu" "In6.Cu")
			(hatch none 0.5)
			(connect_pads
				(clearance 0)
			)
			(min_thickness 0.25)
			(keepout
				(tracks not_allowed)
				(vias allowed)
				(pads allowed)
				(copperpour not_allowed)
				(footprints allowed)
			)
			(placement
				(enabled no)
				(sheetname "")
			)
			(fill
				(thermal_gap 0.5)
				(thermal_bridge_width 0.5)
				(island_removal_mode 0)
			)
			(polygon
				(pts
					(arc
						(start 8.736838 -77.476858)
						(mid 6.603238 -77.476858)
						(end 8.736838 -77.476858)
					)
				)
			)
		)
	)
	(footprint ""
		(layer "F.Cu")
		(at 46.425612 -253.125732 180)
		(property "Reference" "R99"
			(at 2.224278 1.16205 0)
			(unlocked yes)
			(layer "F.SilkS")
			(effects
				(font
					(size 0.7874 0.5842)
					(thickness 0.1524)
				)
				(justify left)
			)
		)
		(property "Value" ""
			(at 0 0 180)
			(layer "F.Fab")
			(effects
				(font
					(size 1.27 1.27)
				)
			)
		)
		(duplicate_pad_numbers_are_jumpers no)
		(fp_line
			(start 0.7874 0.4064)
			(end -0.7874 0.4064)
			(stroke
				(width 0.1524)
				(type default)
			)
			(layer "F.SilkS")
		)
		(fp_line
			(start 0.7874 -0.4064)
			(end 0.7874 0.4064)
			(stroke
				(width 0.1524)
				(type default)
			)
			(layer "F.SilkS")
		)
		(fp_line
			(start -0.7874 0.4064)
			(end -0.7874 -0.4064)
			(stroke
				(width 0.1524)
				(type default)
			)
			(layer "F.SilkS")
		)
		(fp_line
			(start -0.7874 -0.4064)
			(end 0.7874 -0.4064)
			(stroke
				(width 0.1524)
				(type default)
			)
			(layer "F.SilkS")
		)
		(fp_poly
			(pts
				(xy -0.508 0.2794) (xy -0.508 0.2286) (xy -0.635 0.2286) (xy -0.635 -0.254) (xy -0.5334 -0.254)
				(xy -0.5334 -0.2794) (xy 0.5334 -0.2794) (xy 0.5334 -0.254) (xy 0.635 -0.254) (xy 0.635 0.254) (xy 0.5334 0.254)
				(xy 0.5334 0.2794)
			)
			(stroke
				(width 0)
				(type default)
			)
			(fill no)
			(layer "F.CrtYd")
		)
		(pad "1" smd rect
			(at 0.40005 0 180)
			(size 0.4572 0.508)
			(layers "F.Cu" "F.Mask" "F.Paste")
			(net "PSU6_REMOTE_R_N")
		)
		(pad "2" smd rect
			(at -0.40005 0 180)
			(size 0.4572 0.508)
			(layers "F.Cu" "F.Mask" "F.Paste")
			(net "GND")
		)
	)
	(footprint ""
		(layer "F.Cu")
		(at 91.399868 -242.26012)
		(property "Reference" "H18"
			(at -5.1308 -5.23113 0)
			(unlocked yes)
			(layer "F.SilkS")
			(effects
				(font
					(size 0.7874 0.5842)
					(thickness 0.1524)
				)
				(justify left)
			)
		)
		(property "Value" ""
			(at 0 0 0)
			(layer "F.Fab")
			(effects
				(font
					(size 1.27 1.27)
				)
			)
		)
		(duplicate_pad_numbers_are_jumpers no)
		(fp_circle
			(center 0 0)
			(end 4.826 0)
			(stroke
				(width 0.1524)
				(type default)
			)
			(fill no)
			(layer "F.SilkS")
		)
		(fp_circle
			(center 0 0)
			(end 4.826 0)
			(stroke
				(width 0.1524)
				(type default)
			)
			(fill no)
			(layer "B.SilkS")
		)
		(fp_poly
			(pts
				(arc
					(start 0 4.0132)
					(mid 0 -4.0132)
					(end 0 4.0132)
				)
			)
			(stroke
				(width 0)
				(type default)
			)
			(fill no)
			(layer "F.CrtYd")
		)
		(pad "" np_thru_hole circle
			(at 0 0)
			(size 8.001 8.001)
			(drill 8.001)
			(layers "*.Cu" "*.Mask")
			(clearance 0.381)
			(thermal_gap 0.381)
		)
		(zone
			(layers "F.Cu" "B.Cu" "In1.Cu" "In2.Cu" "In3.Cu" "In4.Cu" "In5.Cu" "In6.Cu")
			(hatch none 0.5)
			(connect_pads
				(clearance 0)
			)
			(min_thickness 0.25)
			(keepout
				(tracks not_allowed)
				(vias allowed)
				(pads allowed)
				(copperpour not_allowed)
				(footprints allowed)
			)
			(placement
				(enabled no)
				(sheetname "")
			)
			(fill
				(thermal_gap 0.5)
				(thermal_bridge_width 0.5)
				(island_removal_mode 0)
			)
			(polygon
				(pts
					(arc
						(start 91.399868 -237.73892)
						(mid 91.399868 -246.78132)
						(end 91.399868 -237.73892)
					)
				)
			)
		)
	)
	(footprint ""
		(layer "F.Cu")
		(at 13.420852 -318.358012 180)
		(property "Reference" "R140"
			(at -2.29235 -0.183642 0)
			(unlocked yes)
			(layer "F.SilkS")
			(effects
				(font
					(size 0.7874 0.5842)
					(thickness 0.1524)
				)
				(justify left)
			)
		)
		(property "Value" ""
			(at 0 0 180)
			(layer "F.Fab")
			(effects
				(font
					(size 1.27 1.27)
				)
			)
		)
		(duplicate_pad_numbers_are_jumpers no)
		(fp_line
			(start 0.7874 0.4064)
			(end -0.7874 0.4064)
			(stroke
				(width 0.1524)
				(type default)
			)
			(layer "F.SilkS")
		)
		(fp_line
			(start 0.7874 -0.4064)
			(end 0.7874 0.4064)
			(stroke
				(width 0.1524)
				(type default)
			)
			(layer "F.SilkS")
		)
		(fp_line
			(start -0.7874 0.4064)
			(end -0.7874 -0.4064)
			(stroke
				(width 0.1524)
				(type default)
			)
			(layer "F.SilkS")
		)
		(fp_line
			(start -0.7874 -0.4064)
			(end 0.7874 -0.4064)
			(stroke
				(width 0.1524)
				(type default)
			)
			(layer "F.SilkS")
		)
		(fp_poly
			(pts
				(xy -0.508 0.2794) (xy -0.508 0.2286) (xy -0.635 0.2286) (xy -0.635 -0.254) (xy -0.5334 -0.254)
				(xy -0.5334 -0.2794) (xy 0.5334 -0.2794) (xy 0.5334 -0.254) (xy 0.635 -0.254) (xy 0.635 0.254) (xy 0.5334 0.254)
				(xy 0.5334 0.2794)
			)
			(stroke
				(width 0)
				(type default)
			)
			(fill no)
			(layer "F.CrtYd")
		)
		(pad "1" smd rect
			(at 0.40005 0 180)
			(size 0.4572 0.508)
			(layers "F.Cu" "F.Mask" "F.Paste")
			(net "FAN_PWM")
		)
		(pad "2" smd rect
			(at -0.40005 0 180)
			(size 0.4572 0.508)
			(layers "F.Cu" "F.Mask" "F.Paste")
			(net "GND")
		)
	)
	(footprint ""
		(layer "F.Cu")
		(at 73.914508 -108.56976 -90)
		(property "Reference" "C17"
			(at -2.68224 -0.080772 90)
			(unlocked yes)
			(layer "F.SilkS")
			(effects
				(font
					(size 0.7874 0.5842)
					(thickness 0.1524)
				)
				(justify left)
			)
		)
		(property "Value" ""
			(at 0 0 270)
			(layer "F.Fab")
			(effects
				(font
					(size 1.27 1.27)
				)
			)
		)
		(duplicate_pad_numbers_are_jumpers no)
		(fp_line
			(start -0.7874 0.4064)
			(end -0.7874 -0.4064)
			(stroke
				(width 0.1524)
				(type default)
			)
			(layer "F.SilkS")
		)
		(fp_line
			(start 0.7874 0.4064)
			(end -0.7874 0.4064)
			(stroke
				(width 0.1524)
				(type default)
			)
			(layer "F.SilkS")
		)
		(fp_line
			(start 0 0.381)
			(end 0 -0.381)
			(stroke
				(width 0.1524)
				(type default)
			)
			(layer "F.SilkS")
		)
		(fp_line
			(start -0.7874 -0.4064)
			(end 0.7874 -0.4064)
			(stroke
				(width 0.1524)
				(type default)
			)
			(layer "F.SilkS")
		)
		(fp_line
			(start 0.7874 -0.4064)
			(end 0.7874 0.4064)
			(stroke
				(width 0.1524)
				(type default)
			)
			(layer "F.SilkS")
		)
		(fp_poly
			(pts
				(xy -0.5334 0.254) (xy -0.635 0.254) (xy -0.635 0.2286) (xy -0.635 -0.254) (xy -0.5334 -0.254) (xy -0.5334 -0.2794)
				(xy 0.5334 -0.2794) (xy 0.5334 -0.254) (xy 0.635 -0.254) (xy 0.635 0.254) (xy 0.5334 0.254) (xy 0.5334 0.2794)
				(xy -0.508 0.2794) (xy -0.5334 0.2794)
			)
			(stroke
				(width 0)
				(type default)
			)
			(fill no)
			(layer "F.CrtYd")
		)
		(pad "1" smd rect
			(at 0.40005 0 270)
			(size 0.4572 0.508)
			(layers "F.Cu" "F.Mask" "F.Paste")
			(net "P12V")
		)
		(pad "2" smd rect
			(at -0.40005 0 270)
			(size 0.4572 0.508)
			(layers "F.Cu" "F.Mask" "F.Paste")
			(net "GND")
		)
	)
	(footprint ""
		(layer "F.Cu")
		(at 66.74104 -206.29118 180)
		(property "Reference" "R120"
			(at -0.150876 -1.42875 0)
			(unlocked yes)
			(layer "F.SilkS")
			(effects
				(font
					(size 0.7874 0.5842)
					(thickness 0.1524)
				)
				(justify left)
			)
		)
		(property "Value" ""
			(at 0 0 180)
			(layer "F.Fab")
			(effects
				(font
					(size 1.27 1.27)
				)
			)
		)
		(duplicate_pad_numbers_are_jumpers no)
		(fp_line
			(start 0.7874 0.4064)
			(end -0.7874 0.4064)
			(stroke
				(width 0.1524)
				(type default)
			)
			(layer "F.SilkS")
		)
		(fp_line
			(start 0.7874 -0.4064)
			(end 0.7874 0.4064)
			(stroke
				(width 0.1524)
				(type default)
			)
			(layer "F.SilkS")
		)
		(fp_line
			(start -0.7874 0.4064)
			(end -0.7874 -0.4064)
			(stroke
				(width 0.1524)
				(type default)
			)
			(layer "F.SilkS")
		)
		(fp_line
			(start -0.7874 -0.4064)
			(end 0.7874 -0.4064)
			(stroke
				(width 0.1524)
				(type default)
			)
			(layer "F.SilkS")
		)
		(fp_poly
			(pts
				(xy -0.508 0.2794) (xy -0.508 0.2286) (xy -0.635 0.2286) (xy -0.635 -0.254) (xy -0.5334 -0.254)
				(xy -0.5334 -0.2794) (xy 0.5334 -0.2794) (xy 0.5334 -0.254) (xy 0.635 -0.254) (xy 0.635 0.254) (xy 0.5334 0.254)
				(xy 0.5334 0.2794)
			)
			(stroke
				(width 0)
				(type default)
			)
			(fill no)
			(layer "F.CrtYd")
		)
		(pad "1" smd rect
			(at 0.40005 0 180)
			(size 0.4572 0.508)
			(layers "F.Cu" "F.Mask" "F.Paste")
			(net "PSU3_REMOTE_R2_N")
		)
		(pad "2" smd rect
			(at -0.40005 0 180)
			(size 0.4572 0.508)
			(layers "F.Cu" "F.Mask" "F.Paste")
			(net "GND")
		)
	)
	(footprint ""
		(layer "F.Cu")
		(at 39.512494 -463.972148 90)
		(property "Reference" "R130"
			(at -0.669544 1.862074 0)
			(unlocked yes)
			(layer "F.SilkS")
			(effects
				(font
					(size 0.7874 0.5842)
					(thickness 0.1524)
				)
				(justify left)
			)
		)
		(property "Value" ""
			(at 0 0 90)
			(layer "F.Fab")
			(effects
				(font
					(size 1.27 1.27)
				)
			)
		)
		(duplicate_pad_numbers_are_jumpers no)
		(fp_line
			(start 0.7874 -0.4064)
			(end 0.7874 0.4064)
			(stroke
				(width 0.1524)
				(type default)
			)
			(layer "F.SilkS")
		)
		(fp_line
			(start -0.7874 -0.4064)
			(end 0.7874 -0.4064)
			(stroke
				(width 0.1524)
				(type default)
			)
			(layer "F.SilkS")
		)
		(fp_line
			(start 0.7874 0.4064)
			(end -0.7874 0.4064)
			(stroke
				(width 0.1524)
				(type default)
			)
			(layer "F.SilkS")
		)
		(fp_line
			(start -0.7874 0.4064)
			(end -0.7874 -0.4064)
			(stroke
				(width 0.1524)
				(type default)
			)
			(layer "F.SilkS")
		)
		(fp_poly
			(pts
				(xy -0.508 0.2794) (xy -0.508 0.2286) (xy -0.635 0.2286) (xy -0.635 -0.254) (xy -0.5334 -0.254)
				(xy -0.5334 -0.2794) (xy 0.5334 -0.2794) (xy 0.5334 -0.254) (xy 0.635 -0.254) (xy 0.635 0.254) (xy 0.5334 0.254)
				(xy 0.5334 0.2794)
			)
			(stroke
				(width 0)
				(type default)
			)
			(fill no)
			(layer "F.CrtYd")
		)
		(pad "1" smd rect
			(at 0.40005 0 90)
			(size 0.4572 0.508)
			(layers "F.Cu" "F.Mask" "F.Paste")
			(net "PSU6_REMOTE_P")
		)
		(pad "2" smd rect
			(at -0.40005 0 90)
			(size 0.4572 0.508)
			(layers "F.Cu" "F.Mask" "F.Paste")
			(net "PSU6_REMOTE_R2_P")
		)
	)
)
